(kicad_pcb
	(version 20241229)
	(generator "pcbnew")
	(generator_version "9.0")
	(general
		(thickness 1.6296)
		(legacy_teardrops no)
	)
	(paper "A3")
	(title_block
		(title "Thunderbolt to 10GbE adapter")
		(date "2026-04-21")
		(rev "1.1.0")
		(company "Antmicro Ltd")
		(comment 1 "www.antmicro.com")
		(comment 9 "footprints 388-392 of 703")
	)
	(layers
		(0 "F.Cu" signal)
		(4 "In1.Cu" signal)
		(6 "In2.Cu" signal)
		(8 "In3.Cu" signal)
		(10 "In4.Cu" signal)
		(12 "In5.Cu" signal)
		(14 "In6.Cu" signal)
		(2 "B.Cu" signal)
		(9 "F.Adhes" user "F.Adhesive")
		(11 "B.Adhes" user "B.Adhesive")
		(13 "F.Paste" user)
		(15 "B.Paste" user)
		(5 "F.SilkS" user "F.Silkscreen")
		(7 "B.SilkS" user "B.Silkscreen")
		(1 "F.Mask" user)
		(3 "B.Mask" user)
		(17 "Dwgs.User" user "User.Drawings")
		(19 "Cmts.User" user "User.Comments")
		(21 "Eco1.User" user "User.Eco1")
		(23 "Eco2.User" user "User.Eco2")
		(25 "Edge.Cuts" user)
		(27 "Margin" user)
		(31 "F.CrtYd" user "F.Courtyard")
		(29 "B.CrtYd" user "B.Courtyard")
		(35 "F.Fab" user)
		(33 "B.Fab" user)
	)
	(footprint "antmicro-footprints:R_0402_1005Metric"
		(layer "B.Cu")
		(at 135.761535 138.807574 90)
		(descr "Resistor SMD 0402")
		(tags "resistor SMD 0402")
		(property "Reference" "R26"
			(at 9.557574 19.525001 270)
			(layer "B.SilkS")
			(effects
				(font
					(size 0.7 0.7)
					(thickness 0.15)
				)
				(justify mirror)
			)
		)
		(property "Value" "R_10k_0402"
			(at -1.011843 -1.772047 270)
			(layer "B.Fab")
			(effects
				(font
					(size 0.7 0.7)
					(thickness 0.15)
				)
				(justify left bottom mirror)
			)
		)
		(property "Datasheet" "https://www.bourns.com/docs/product-datasheets/cr.pdf"
			(at 0 0 270)
			(layer "B.Fab")
			(hide yes)
			(effects
				(font
					(size 1.27 1.27)
					(thickness 0.15)
				)
				(justify mirror)
			)
		)
		(property "Description" "SMD Chip Resistor, 10 kohm, ± 1%, 62.5 mW, 0402 [1005 Metric], Thick Film, General Purpose"
			(at 0 0 270)
			(layer "B.Fab")
			(hide yes)
			(effects
				(font
					(size 1.27 1.27)
					(thickness 0.15)
				)
				(justify mirror)
			)
		)
		(property "MPN" "CR0402-FX-1002GLF"
			(at 0 0 90)
			(unlocked yes)
			(layer "B.Fab")
			(hide yes)
			(effects
				(font
					(size 1 1)
					(thickness 0.15)
				)
				(justify mirror)
			)
		)
		(property "Manufacturer" "Bourns"
			(at 0 0 90)
			(unlocked yes)
			(layer "B.Fab")
			(hide yes)
			(effects
				(font
					(size 1 1)
					(thickness 0.15)
				)
				(justify mirror)
			)
		)
		(property "License" "Apache-2.0"
			(at 0 0 90)
			(unlocked yes)
			(layer "B.Fab")
			(hide yes)
			(effects
				(font
					(size 1 1)
					(thickness 0.15)
				)
				(justify mirror)
			)
		)
		(property "Val" "10k"
			(at 0 0 90)
			(unlocked yes)
			(layer "B.Fab")
			(hide yes)
			(effects
				(font
					(size 1 1)
					(thickness 0.15)
				)
				(justify mirror)
			)
		)
		(property "Tolerance" "1%"
			(at 0 0 90)
			(unlocked yes)
			(layer "B.Fab")
			(hide yes)
			(effects
				(font
					(size 1 1)
					(thickness 0.15)
				)
				(justify mirror)
			)
		)
		(property "Author" "Antmicro"
			(at 0 0 90)
			(unlocked yes)
			(layer "B.Fab")
			(hide yes)
			(effects
				(font
					(size 1 1)
					(thickness 0.15)
				)
				(justify mirror)
			)
		)
		(sheetname "/PD and TB DC-DC/")
		(sheetfile "PD_and_TB_DC_DC.kicad_sch")
		(attr smd)
		(fp_rect
			(start -0.925 0.47)
			(end 0.925 -0.47)
			(stroke
				(width 0.05)
				(type default)
			)
			(fill no)
			(layer "B.CrtYd")
		)
		(fp_rect
			(start -0.5 0.25)
			(end 0.5 -0.25)
			(stroke
				(width 0.15)
				(type solid)
			)
			(fill no)
			(layer "B.Fab")
		)
		(fp_text user "Author: Antmicro"
			(at -0.95 -4.169 270)
			(layer "B.Fab")
			(effects
				(font
					(size 0.7 0.7)
					(thickness 0.15)
				)
				(justify left bottom mirror)
			)
		)
		(fp_text user "${REFERENCE}"
			(at -0.95 -3.168 270)
			(layer "B.Fab")
			(effects
				(font
					(size 0.7 0.7)
					(thickness 0.15)
				)
				(justify left bottom mirror)
			)
		)
		(fp_text user "License: Apache-2.0"
			(at -0.95 -5.169 270)
			(layer "B.Fab")
			(effects
				(font
					(size 0.7 0.7)
					(thickness 0.15)
				)
				(justify left bottom mirror)
			)
		)
		(pad "1" smd roundrect
			(at -0.48 0 90)
			(size 0.59 0.64)
			(layers "B.Cu" "B.Mask" "B.Paste")
			(roundrect_rratio 0.25)
			(net 209 "Net-(U3-MRESET(GPIO11))")
			(pintype "passive")
		)
		(pad "2" smd roundrect
			(at 0.48 0 90)
			(size 0.59 0.64)
			(layers "B.Cu" "B.Mask" "B.Paste")
			(roundrect_rratio 0.25)
			(net 23 "GND")
			(pintype "passive")
		)
	)
	(footprint "antmicro-footprints:C_0402_1005Metric"
		(layer "B.Cu")
		(at 126.224999 122.000001 -90)
		(descr "Capacitor SMD 0402")
		(tags "capacitor SMD 0402")
		(property "Reference" "C66"
			(at -7.700002 -21.900002 90)
			(layer "B.SilkS")
			(effects
				(font
					(size 0.7 0.7)
					(thickness 0.15)
				)
				(justify mirror)
			)
		)
		(property "Value" "C_1u_0402"
			(at -1.022927 -2.155213 90)
			(layer "B.Fab")
			(effects
				(font
					(size 0.7 0.7)
					(thickness 0.15)
				)
				(justify left bottom mirror)
			)
		)
		(property "Datasheet" "https://product.tdk.com/en/search/capacitor/ceramic/mlcc/info?part_no=C1005X6S1A105K050BC"
			(at 0 0 90)
			(layer "B.Fab")
			(hide yes)
			(effects
				(font
					(size 1.27 1.27)
					(thickness 0.15)
				)
				(justify mirror)
			)
		)
		(property "Description" "SMD Multilayer Ceramic Capacitor, 1 µF, 10 V, 0402 [1005 Metric], ± 10%, X6S, C"
			(at 0 0 90)
			(layer "B.Fab")
			(hide yes)
			(effects
				(font
					(size 1.27 1.27)
					(thickness 0.15)
				)
				(justify mirror)
			)
		)
		(property "MPN" "C1005X6S1A105K050BC"
			(at 0 0 270)
			(unlocked yes)
			(layer "B.Fab")
			(hide yes)
			(effects
				(font
					(size 1 1)
					(thickness 0.15)
				)
				(justify mirror)
			)
		)
		(property "Manufacturer" "TDK"
			(at 0 0 270)
			(unlocked yes)
			(layer "B.Fab")
			(hide yes)
			(effects
				(font
					(size 1 1)
					(thickness 0.15)
				)
				(justify mirror)
			)
		)
		(property "License" "Apache-2.0"
			(at 0 0 270)
			(unlocked yes)
			(layer "B.Fab")
			(hide yes)
			(effects
				(font
					(size 1 1)
					(thickness 0.15)
				)
				(justify mirror)
			)
		)
		(property "Val" "1u"
			(at 0 0 270)
			(unlocked yes)
			(layer "B.Fab")
			(hide yes)
			(effects
				(font
					(size 1 1)
					(thickness 0.15)
				)
				(justify mirror)
			)
		)
		(property "Voltage" ""
			(at 0 0 270)
			(unlocked yes)
			(layer "B.Fab")
			(hide yes)
			(effects
				(font
					(size 1 1)
					(thickness 0.15)
				)
				(justify mirror)
			)
		)
		(property "Dielectric" ""
			(at 0 0 270)
			(unlocked yes)
			(layer "B.Fab")
			(hide yes)
			(effects
				(font
					(size 1 1)
					(thickness 0.15)
				)
				(justify mirror)
			)
		)
		(property "Author" "Antmicro"
			(at 0 0 270)
			(unlocked yes)
			(layer "B.Fab")
			(hide yes)
			(effects
				(font
					(size 1 1)
					(thickness 0.15)
				)
				(justify mirror)
			)
		)
		(sheetname "/TB Controller - Power/")
		(sheetfile "tb-power.kicad_sch")
		(attr smd)
		(fp_rect
			(start -0.925 0.47)
			(end 0.925 -0.47)
			(stroke
				(width 0.05)
				(type default)
			)
			(fill no)
			(layer "B.CrtYd")
		)
		(fp_line
			(start -0.494 0.25)
			(end 0.504 0.25)
			(stroke
				(width 0.15)
				(type solid)
			)
			(layer "B.Fab")
		)
		(fp_line
			(start 0.504 0.25)
			(end 0.504 -0.248)
			(stroke
				(width 0.15)
				(type solid)
			)
			(layer "B.Fab")
		)
		(fp_line
			(start -0.494 -0.248)
			(end -0.494 0.25)
			(stroke
				(width 0.15)
				(type solid)
			)
			(layer "B.Fab")
		)
		(fp_line
			(start 0.504 -0.248)
			(end -0.494 -0.248)
			(stroke
				(width 0.15)
				(type solid)
			)
			(layer "B.Fab")
		)
		(fp_text user "${REFERENCE}"
			(at -0.939 -4.599 90)
			(layer "B.Fab")
			(effects
				(font
					(size 0.7 0.7)
					(thickness 0.15)
				)
				(justify left bottom mirror)
			)
		)
		(fp_text user "Author: Antmicro"
			(at -0.939 -3.399 90)
			(layer "B.Fab")
			(effects
				(font
					(size 0.7 0.7)
					(thickness 0.15)
				)
				(justify left bottom mirror)
			)
		)
		(fp_text user "License: Apache-2.0"
			(at -0.939 -5.799 90)
			(layer "B.Fab")
			(effects
				(font
					(size 0.7 0.7)
					(thickness 0.15)
				)
				(justify left bottom mirror)
			)
		)
		(pad "1" smd roundrect
			(at -0.48 0 270)
			(size 0.59 0.64)
			(layers "B.Cu" "B.Mask" "B.Paste")
			(roundrect_rratio 0.25)
			(net 23 "GND")
			(pintype "passive")
		)
		(pad "2" smd roundrect
			(at 0.48 0 270)
			(size 0.59 0.64)
			(layers "B.Cu" "B.Mask" "B.Paste")
			(roundrect_rratio 0.25)
			(net 405 "Net-(C66-Pad2)")
			(pintype "passive")
		)
	)
	(footprint "antmicro-footprints:C_0402_1005Metric"
		(layer "B.Cu")
		(at 133.849999 137.099998 90)
		(descr "Capacitor SMD 0402")
		(tags "capacitor SMD 0402")
		(property "Reference" "C23"
			(at 8.339997 19.525001 270)
			(layer "B.SilkS")
			(effects
				(font
					(size 0.7 0.7)
					(thickness 0.15)
				)
				(justify mirror)
			)
		)
		(property "Value" "C_220n_0402"
			(at -1.022927 -2.155213 270)
			(layer "B.Fab")
			(effects
				(font
					(size 0.7 0.7)
					(thickness 0.15)
				)
				(justify left bottom mirror)
			)
		)
		(property "Datasheet" "https://www.yageo.com/en/Chart/Download/pdf/CC0402KRX5R6BB224"
			(at 0 0 270)
			(layer "B.Fab")
			(hide yes)
			(effects
				(font
					(size 1.27 1.27)
					(thickness 0.15)
				)
				(justify mirror)
			)
		)
		(property "Description" "SMD Multilayer Ceramic Capacitor, 0.22 µF, 10 V, 0402 [1005 Metric], ± 10%, X5R, CC Series"
			(at 0 0 270)
			(layer "B.Fab")
			(hide yes)
			(effects
				(font
					(size 1.27 1.27)
					(thickness 0.15)
				)
				(justify mirror)
			)
		)
		(property "MPN" "CC0402KRX5R6BB224"
			(at 0 0 90)
			(unlocked yes)
			(layer "B.Fab")
			(hide yes)
			(effects
				(font
					(size 1 1)
					(thickness 0.15)
				)
				(justify mirror)
			)
		)
		(property "Manufacturer" "YAGEO"
			(at 0 0 90)
			(unlocked yes)
			(layer "B.Fab")
			(hide yes)
			(effects
				(font
					(size 1 1)
					(thickness 0.15)
				)
				(justify mirror)
			)
		)
		(property "License" "Apache-2.0"
			(at 0 0 90)
			(unlocked yes)
			(layer "B.Fab")
			(hide yes)
			(effects
				(font
					(size 1 1)
					(thickness 0.15)
				)
				(justify mirror)
			)
		)
		(property "Val" "220n"
			(at 0 0 90)
			(unlocked yes)
			(layer "B.Fab")
			(hide yes)
			(effects
				(font
					(size 1 1)
					(thickness 0.15)
				)
				(justify mirror)
			)
		)
		(property "Voltage" ""
			(at 0 0 90)
			(unlocked yes)
			(layer "B.Fab")
			(hide yes)
			(effects
				(font
					(size 1 1)
					(thickness 0.15)
				)
				(justify mirror)
			)
		)
		(property "Dielectric" ""
			(at 0 0 90)
			(unlocked yes)
			(layer "B.Fab")
			(hide yes)
			(effects
				(font
					(size 1 1)
					(thickness 0.15)
				)
				(justify mirror)
			)
		)
		(property "Author" "Antmicro"
			(at 0 0 90)
			(unlocked yes)
			(layer "B.Fab")
			(hide yes)
			(effects
				(font
					(size 1 1)
					(thickness 0.15)
				)
				(justify mirror)
			)
		)
		(sheetname "/PD and TB DC-DC/")
		(sheetfile "PD_and_TB_DC_DC.kicad_sch")
		(attr smd)
		(fp_rect
			(start -0.925 0.47)
			(end 0.925 -0.47)
			(stroke
				(width 0.05)
				(type default)
			)
			(fill no)
			(layer "B.CrtYd")
		)
		(fp_line
			(start 0.504 -0.248)
			(end -0.494 -0.248)
			(stroke
				(width 0.15)
				(type solid)
			)
			(layer "B.Fab")
		)
		(fp_line
			(start -0.494 -0.248)
			(end -0.494 0.25)
			(stroke
				(width 0.15)
				(type solid)
			)
			(layer "B.Fab")
		)
		(fp_line
			(start 0.504 0.25)
			(end 0.504 -0.248)
			(stroke
				(width 0.15)
				(type solid)
			)
			(layer "B.Fab")
		)
		(fp_line
			(start -0.494 0.25)
			(end 0.504 0.25)
			(stroke
				(width 0.15)
				(type solid)
			)
			(layer "B.Fab")
		)
		(fp_text user "License: Apache-2.0"
			(at -0.939 -5.799 270)
			(layer "B.Fab")
			(effects
				(font
					(size 0.7 0.7)
					(thickness 0.15)
				)
				(justify left bottom mirror)
			)
		)
		(fp_text user "${REFERENCE}"
			(at -0.939 -4.599 270)
			(layer "B.Fab")
			(effects
				(font
					(size 0.7 0.7)
					(thickness 0.15)
				)
				(justify left bottom mirror)
			)
		)
		(fp_text user "Author: Antmicro"
			(at -0.939 -3.399 270)
			(layer "B.Fab")
			(effects
				(font
					(size 0.7 0.7)
					(thickness 0.15)
				)
				(justify left bottom mirror)
			)
		)
		(pad "1" smd roundrect
			(at -0.48 0 90)
			(size 0.59 0.64)
			(layers "B.Cu" "B.Mask" "B.Paste")
			(roundrect_rratio 0.25)
			(net 23 "GND")
			(pintype "passive")
		)
		(pad "2" smd roundrect
			(at 0.48 0 90)
			(size 0.59 0.64)
			(layers "B.Cu" "B.Mask" "B.Paste")
			(roundrect_rratio 0.25)
			(net 165 "Net-(U3-SS)")
			(pintype "passive")
		)
	)
	(footprint "antmicro-footprints:R_0402_1005Metric"
		(layer "B.Cu")
		(at 150.681866 92.485116 90)
		(descr "Resistor SMD 0402")
		(tags "resistor SMD 0402")
		(property "Reference" "R149"
			(at -10.814884 18.718134 270)
			(layer "B.SilkS")
			(effects
				(font
					(size 0.7 0.7)
					(thickness 0.15)
				)
				(justify mirror)
			)
		)
		(property "Value" "R_100R_0402"
			(at -1.011843 -1.772047 270)
			(layer "B.Fab")
			(effects
				(font
					(size 0.7 0.7)
					(thickness 0.15)
				)
				(justify left bottom mirror)
			)
		)
		(property "Datasheet" "https://www.bourns.com/docs/product-datasheets/cr.pdf"
			(at 0 0 270)
			(layer "B.Fab")
			(hide yes)
			(effects
				(font
					(size 1.27 1.27)
					(thickness 0.15)
				)
				(justify mirror)
			)
		)
		(property "Description" "SMD Chip Resistor, 100 ohm, ± 1%, 62.5 mW, 0402 [1005 Metric], Thick Film, General Purpose"
			(at 0 0 270)
			(layer "B.Fab")
			(hide yes)
			(effects
				(font
					(size 1.27 1.27)
					(thickness 0.15)
				)
				(justify mirror)
			)
		)
		(property "MPN" "CR0402-FX-1000GLF"
			(at 0 0 90)
			(unlocked yes)
			(layer "B.Fab")
			(hide yes)
			(effects
				(font
					(size 1 1)
					(thickness 0.15)
				)
				(justify mirror)
			)
		)
		(property "Manufacturer" "Bourns"
			(at 0 0 90)
			(unlocked yes)
			(layer "B.Fab")
			(hide yes)
			(effects
				(font
					(size 1 1)
					(thickness 0.15)
				)
				(justify mirror)
			)
		)
		(property "License" "Apache-2.0"
			(at 0 0 90)
			(unlocked yes)
			(layer "B.Fab")
			(hide yes)
			(effects
				(font
					(size 1 1)
					(thickness 0.15)
				)
				(justify mirror)
			)
		)
		(property "Author" "Antmicro"
			(at 0 0 90)
			(unlocked yes)
			(layer "B.Fab")
			(hide yes)
			(effects
				(font
					(size 1 1)
					(thickness 0.15)
				)
				(justify mirror)
			)
		)
		(property "Val" "100R"
			(at 0 0 90)
			(unlocked yes)
			(layer "B.Fab")
			(hide yes)
			(effects
				(font
					(size 1 1)
					(thickness 0.15)
				)
				(justify mirror)
			)
		)
		(property "Tolerance" "1%"
			(at 0 0 90)
			(unlocked yes)
			(layer "B.Fab")
			(hide yes)
			(effects
				(font
					(size 1 1)
					(thickness 0.15)
				)
				(justify mirror)
			)
		)
		(sheetname "/X710-AT2 Misc/")
		(sheetfile "x710-at2-mics.kicad_sch")
		(attr smd)
		(fp_rect
			(start -0.925 0.47)
			(end 0.925 -0.47)
			(stroke
				(width 0.05)
				(type default)
			)
			(fill no)
			(layer "B.CrtYd")
		)
		(fp_rect
			(start -0.5 0.25)
			(end 0.5 -0.25)
			(stroke
				(width 0.15)
				(type solid)
			)
			(fill no)
			(layer "B.Fab")
		)
		(fp_text user "${REFERENCE}"
			(at -0.95 -3.168 270)
			(layer "B.Fab")
			(effects
				(font
					(size 0.7 0.7)
					(thickness 0.15)
				)
				(justify left bottom mirror)
			)
		)
		(fp_text user "Author: Antmicro"
			(at -0.95 -4.169 270)
			(layer "B.Fab")
			(effects
				(font
					(size 0.7 0.7)
					(thickness 0.15)
				)
				(justify left bottom mirror)
			)
		)
		(fp_text user "License: Apache-2.0"
			(at -0.95 -5.169 270)
			(layer "B.Fab")
			(effects
				(font
					(size 0.7 0.7)
					(thickness 0.15)
				)
				(justify left bottom mirror)
			)
		)
		(pad "1" smd roundrect
			(at -0.48 0 90)
			(size 0.59 0.64)
			(layers "B.Cu" "B.Mask" "B.Paste")
			(roundrect_rratio 0.25)
			(net 23 "GND")
			(pintype "passive")
		)
		(pad "2" smd roundrect
			(at 0.48 0 90)
			(size 0.59 0.64)
			(layers "B.Cu" "B.Mask" "B.Paste")
			(roundrect_rratio 0.25)
			(net 35 "/X710-AT2 Misc/POR_BYPASS")
			(pintype "passive")
		)
	)
	(footprint "antmicro-footprints:C_0402_1005Metric"
		(layer "B.Cu")
		(at 159 136 180)
		(descr "Capacitor SMD 0402")
		(tags "capacitor SMD 0402")
		(property "Reference" "C298"
			(at -1.75 0.5 0)
			(layer "B.SilkS")
			(effects
				(font
					(size 0.7 0.7)
					(thickness 0.15)
				)
				(justify left bottom mirror)
			)
		)
		(property "Value" "C_1u_25V_0402"
			(at -1.022927 -2.155213 0)
			(layer "B.Fab")
			(effects
				(font
					(size 0.7 0.7)
					(thickness 0.15)
				)
				(justify left bottom mirror)
			)
		)
		(property "Datasheet" "https://www.murata.com/products/productdetail?partno=GRM155R61E105KE11%23"
			(at 0 0 0)
			(layer "B.Fab")
			(hide yes)
			(effects
				(font
					(size 1.27 1.27)
					(thickness 0.15)
				)
				(justify mirror)
			)
		)
		(property "Description" "SMD Multilayer Ceramic Capacitor, 1 µF, 25 V, 0402 [1005 Metric], ± 10%, X5R, GRM Series"
			(at 0 0 0)
			(layer "B.Fab")
			(hide yes)
			(effects
				(font
					(size 1.27 1.27)
					(thickness 0.15)
				)
				(justify mirror)
			)
		)
		(property "MPN" "GRM155R61E105KE11J"
			(at 0 0 180)
			(unlocked yes)
			(layer "B.Fab")
			(hide yes)
			(effects
				(font
					(size 1 1)
					(thickness 0.15)
				)
				(justify mirror)
			)
		)
		(property "Manufacturer" "Murata"
			(at 0 0 180)
			(unlocked yes)
			(layer "B.Fab")
			(hide yes)
			(effects
				(font
					(size 1 1)
					(thickness 0.15)
				)
				(justify mirror)
			)
		)
		(property "License" "Apache-2.0"
			(at 0 0 180)
			(unlocked yes)
			(layer "B.Fab")
			(hide yes)
			(effects
				(font
					(size 1 1)
					(thickness 0.15)
				)
				(justify mirror)
			)
		)
		(property "Author" "Antmicro"
			(at 0 0 180)
			(unlocked yes)
			(layer "B.Fab")
			(hide yes)
			(effects
				(font
					(size 1 1)
					(thickness 0.15)
				)
				(justify mirror)
			)
		)
		(property "Val" "1u"
			(at 0 0 180)
			(unlocked yes)
			(layer "B.Fab")
			(hide yes)
			(effects
				(font
					(size 1 1)
					(thickness 0.15)
				)
				(justify mirror)
			)
		)
		(property "Voltage" "25V"
			(at 0 0 180)
			(unlocked yes)
			(layer "B.Fab")
			(hide yes)
			(effects
				(font
					(size 1 1)
					(thickness 0.15)
				)
				(justify mirror)
			)
		)
		(property "Dielectric" "X5R"
			(at 0 0 180)
			(unlocked yes)
			(layer "B.Fab")
			(hide yes)
			(effects
				(font
					(size 1 1)
					(thickness 0.15)
				)
				(justify mirror)
			)
		)
		(sheetname "/2xRJ45/")
		(sheetfile "2xrj45.kicad_sch")
		(attr smd)
		(fp_rect
			(start -0.925 0.47)
			(end 0.925 -0.47)
			(stroke
				(width 0.05)
				(type default)
			)
			(fill no)
			(layer "B.CrtYd")
		)
		(fp_line
			(start 0.504 0.25)
			(end 0.504 -0.248)
			(stroke
				(width 0.15)
				(type solid)
			)
			(layer "B.Fab")
		)
		(fp_line
			(start 0.504 -0.248)
			(end -0.494 -0.248)
			(stroke
				(width 0.15)
				(type solid)
			)
			(layer "B.Fab")
		)
		(fp_line
			(start -0.494 0.25)
			(end 0.504 0.25)
			(stroke
				(width 0.15)
				(type solid)
			)
			(layer "B.Fab")
		)
		(fp_line
			(start -0.494 -0.248)
			(end -0.494 0.25)
			(stroke
				(width 0.15)
				(type solid)
			)
			(layer "B.Fab")
		)
		(fp_text user "${REFERENCE}"
			(at -0.939 -4.599 0)
			(layer "B.Fab")
			(effects
				(font
					(size 0.7 0.7)
					(thickness 0.15)
				)
				(justify left bottom mirror)
			)
		)
		(fp_text user "Author: Antmicro"
			(at -0.939 -3.399 0)
			(layer "B.Fab")
			(effects
				(font
					(size 0.7 0.7)
					(thickness 0.15)
				)
				(justify left bottom mirror)
			)
		)
		(fp_text user "License: Apache-2.0"
			(at -0.939 -5.799 0)
			(layer "B.Fab")
			(effects
				(font
					(size 0.7 0.7)
					(thickness 0.15)
				)
				(justify left bottom mirror)
			)
		)
		(pad "1" smd roundrect
			(at -0.48 0 180)
			(size 0.59 0.64)
			(layers "B.Cu" "B.Mask" "B.Paste")
			(roundrect_rratio 0.25)
			(net 23 "GND")
			(pintype "passive")
		)
		(pad "2" smd roundrect
			(at 0.48 0 180)
			(size 0.59 0.64)
			(layers "B.Cu" "B.Mask" "B.Paste")
			(roundrect_rratio 0.25)
			(net 133 "/2xRJ45/P0_CT")
			(pintype "passive")
		)
	)
)
